(kicad_pcb
	(version 20260206)
	(generator "pcbnew")
	(generator_version "10.0")
	(general
		(thickness 1.6)
		(legacy_teardrops no)
	)
	(paper "A4")
	(title_block
		(title "03242023_DA0F0TMBIJ0_F0T_Motherboard_J_brd_V01_OCP.brd")
		(comment 1 "Grand Teton / footprints 218-223 of 6105")
	)
	(layers
		(0 "F.Cu" signal "TOP")
		(4 "In1.Cu" signal "GND")
		(6 "In2.Cu" signal "IN1")
		(8 "In3.Cu" signal "GND1")
		(10 "In4.Cu" signal "IN2")
		(12 "In5.Cu" signal "GND2")
		(14 "In6.Cu" signal "IN3")
		(16 "In7.Cu" signal "GND3")
		(18 "In8.Cu" signal "VCC")
		(20 "In9.Cu" signal "VCC1")
		(22 "In10.Cu" signal "GND4")
		(24 "In11.Cu" signal "IN4")
		(26 "In12.Cu" signal "GND5")
		(28 "In13.Cu" signal "IN5")
		(30 "In14.Cu" signal "GND6")
		(32 "In15.Cu" signal "IN6")
		(34 "In16.Cu" signal "GND7")
		(2 "B.Cu" signal "BOTTOM")
		(9 "F.Adhes" user "F.Adhesive")
		(11 "B.Adhes" user "B.Adhesive")
		(13 "F.Paste" user "Package Geometry/Pastemask Top")
		(15 "B.Paste" user "Package Geometry/Pastemask Bottom")
		(5 "F.SilkS" user "Ref Des/Silkscreen Top")
		(7 "B.SilkS" user "Ref Des/Silkscreen Bottom")
		(1 "F.Mask" user "Board Geometry/Soldermask Top")
		(3 "B.Mask" user "Board Geometry/Soldermask Bottom")
		(17 "Dwgs.User" user "User.Drawings")
		(19 "Cmts.User" user "User.Comments")
		(21 "Eco1.User" user "User.Eco1")
		(23 "Eco2.User" user "User.Eco2")
		(25 "Edge.Cuts" user "Board Geometry/Outline")
		(27 "Margin" user)
		(31 "F.CrtYd" user "Package Geometry/Place Bound Top")
		(29 "B.CrtYd" user "Package Geometry/Place Bound Bottom")
		(35 "F.Fab" user "Ref Des/Assembly Top")
		(33 "B.Fab" user "Ref Des/Assembly Bottom")
	)
	(footprint ""
		(layer "F.Cu")
		(at 102.67061 -74.95921 -90)
		(property "Reference" "R3074"
			(at 0 0 270)
			(layer "F.SilkS")
			(hide yes)
			(effects
				(font
					(size 1.27 1.27)
				)
			)
		)
		(property "Value" ""
			(at 0 0 270)
			(layer "F.Fab")
			(effects
				(font
					(size 1.27 1.27)
				)
			)
		)
		(duplicate_pad_numbers_are_jumpers no)
		(fp_line
			(start -0.7874 0.4064)
			(end -0.7874 -0.4064)
			(stroke
				(width 0.1524)
				(type default)
			)
			(layer "F.SilkS")
		)
		(fp_line
			(start 0.7874 0.4064)
			(end -0.7874 0.4064)
			(stroke
				(width 0.1524)
				(type default)
			)
			(layer "F.SilkS")
		)
		(fp_line
			(start -0.7874 -0.4064)
			(end 0.7874 -0.4064)
			(stroke
				(width 0.1524)
				(type default)
			)
			(layer "F.SilkS")
		)
		(fp_line
			(start 0.7874 -0.4064)
			(end 0.7874 0.4064)
			(stroke
				(width 0.1524)
				(type default)
			)
			(layer "F.SilkS")
		)
		(fp_line
			(start -0.67945 0.3048)
			(end -0.67945 -0.305054)
			(stroke
				(width 0.1)
				(type default)
			)
			(layer "F.Fab")
		)
		(fp_line
			(start -0.12065 0.3048)
			(end -0.67945 0.3048)
			(stroke
				(width 0.1)
				(type default)
			)
			(layer "F.Fab")
		)
		(fp_line
			(start 0.120396 0.3048)
			(end 0.120396 0.2794)
			(stroke
				(width 0.1)
				(type default)
			)
			(layer "F.Fab")
		)
		(fp_line
			(start 0.67945 0.3048)
			(end 0.120396 0.3048)
			(stroke
				(width 0.1)
				(type default)
			)
			(layer "F.Fab")
		)
		(fp_line
			(start -0.12065 0.2794)
			(end -0.12065 0.3048)
			(stroke
				(width 0.1)
				(type default)
			)
			(layer "F.Fab")
		)
		(fp_line
			(start 0.120396 0.2794)
			(end -0.12065 0.2794)
			(stroke
				(width 0.1)
				(type default)
			)
			(layer "F.Fab")
		)
		(fp_line
			(start -0.12065 -0.2794)
			(end 0.12065 -0.2794)
			(stroke
				(width 0.1)
				(type default)
			)
			(layer "F.Fab")
		)
		(fp_line
			(start 0.12065 -0.2794)
			(end 0.12065 -0.3048)
			(stroke
				(width 0.1)
				(type default)
			)
			(layer "F.Fab")
		)
		(fp_line
			(start 0.12065 -0.3048)
			(end 0.67945 -0.3048)
			(stroke
				(width 0.1)
				(type default)
			)
			(layer "F.Fab")
		)
		(fp_line
			(start 0.67945 -0.3048)
			(end 0.67945 0.3048)
			(stroke
				(width 0.1)
				(type default)
			)
			(layer "F.Fab")
		)
		(fp_line
			(start -0.67945 -0.305054)
			(end -0.12065 -0.305054)
			(stroke
				(width 0.1)
				(type default)
			)
			(layer "F.Fab")
		)
		(fp_line
			(start -0.12065 -0.305054)
			(end -0.12065 -0.2794)
			(stroke
				(width 0.1)
				(type default)
			)
			(layer "F.Fab")
		)
		(pad "1" smd circle
			(at -0.40005 0 270)
			(size 0 0)
			(layers "F.Cu" "F.Mask" "F.Paste")
			(net "LED_RST_RSMRST_PLD_R_N")
		)
		(pad "2" smd circle
			(at 0.40005 0 270)
			(size 0 0)
			(layers "F.Cu" "F.Mask" "F.Paste")
			(net "P3V3_AUX")
		)
	)
	(footprint ""
		(layer "F.Cu")
		(at 162.34283 -77.862938 180)
		(property "Reference" "R3127"
			(at 0 0 180)
			(layer "F.SilkS")
			(hide yes)
			(effects
				(font
					(size 1.27 1.27)
				)
			)
		)
		(property "Value" ""
			(at 0 0 180)
			(layer "F.Fab")
			(effects
				(font
					(size 1.27 1.27)
				)
			)
		)
		(duplicate_pad_numbers_are_jumpers no)
		(fp_line
			(start 0.7874 0.4064)
			(end -0.7874 0.4064)
			(stroke
				(width 0.1524)
				(type default)
			)
			(layer "F.SilkS")
		)
		(fp_line
			(start 0.7874 -0.4064)
			(end 0.7874 0.4064)
			(stroke
				(width 0.1524)
				(type default)
			)
			(layer "F.SilkS")
		)
		(fp_line
			(start -0.7874 0.4064)
			(end -0.7874 -0.4064)
			(stroke
				(width 0.1524)
				(type default)
			)
			(layer "F.SilkS")
		)
		(fp_line
			(start -0.7874 -0.4064)
			(end 0.7874 -0.4064)
			(stroke
				(width 0.1524)
				(type default)
			)
			(layer "F.SilkS")
		)
		(fp_line
			(start 0.67945 0.3048)
			(end 0.120396 0.3048)
			(stroke
				(width 0.1)
				(type default)
			)
			(layer "F.Fab")
		)
		(fp_line
			(start 0.67945 -0.3048)
			(end 0.67945 0.3048)
			(stroke
				(width 0.1)
				(type default)
			)
			(layer "F.Fab")
		)
		(fp_line
			(start 0.12065 -0.2794)
			(end 0.12065 -0.3048)
			(stroke
				(width 0.1)
				(type default)
			)
			(layer "F.Fab")
		)
		(fp_line
			(start 0.12065 -0.3048)
			(end 0.67945 -0.3048)
			(stroke
				(width 0.1)
				(type default)
			)
			(layer "F.Fab")
		)
		(fp_line
			(start 0.120396 0.3048)
			(end 0.120396 0.2794)
			(stroke
				(width 0.1)
				(type default)
			)
			(layer "F.Fab")
		)
		(fp_line
			(start 0.120396 0.2794)
			(end -0.12065 0.2794)
			(stroke
				(width 0.1)
				(type default)
			)
			(layer "F.Fab")
		)
		(fp_line
			(start -0.12065 0.3048)
			(end -0.67945 0.3048)
			(stroke
				(width 0.1)
				(type default)
			)
			(layer "F.Fab")
		)
		(fp_line
			(start -0.12065 0.2794)
			(end -0.12065 0.3048)
			(stroke
				(width 0.1)
				(type default)
			)
			(layer "F.Fab")
		)
		(fp_line
			(start -0.12065 -0.2794)
			(end 0.12065 -0.2794)
			(stroke
				(width 0.1)
				(type default)
			)
			(layer "F.Fab")
		)
		(fp_line
			(start -0.12065 -0.305054)
			(end -0.12065 -0.2794)
			(stroke
				(width 0.1)
				(type default)
			)
			(layer "F.Fab")
		)
		(fp_line
			(start -0.67945 0.3048)
			(end -0.67945 -0.305054)
			(stroke
				(width 0.1)
				(type default)
			)
			(layer "F.Fab")
		)
		(fp_line
			(start -0.67945 -0.305054)
			(end -0.12065 -0.305054)
			(stroke
				(width 0.1)
				(type default)
			)
			(layer "F.Fab")
		)
		(pad "1" smd circle
			(at -0.40005 0 180)
			(size 0 0)
			(layers "F.Cu" "F.Mask" "F.Paste")
			(net "P3V3_AUX")
		)
		(pad "2" smd circle
			(at 0.40005 0 180)
			(size 0 0)
			(layers "F.Cu" "F.Mask" "F.Paste")
			(net "PCA9543_S3M_INT1_N")
		)
	)
	(footprint ""
		(layer "F.Cu")
		(at 449.950078 -412.660084 180)
		(property "Reference" "JP7"
			(at 1.034796 -2.340356 0)
			(unlocked yes)
			(layer "F.SilkS")
			(effects
				(font
					(size 0.7874 0.5842)
					(thickness 0.1524)
				)
				(justify left)
			)
		)
		(property "Value" ""
			(at 0 0 180)
			(layer "F.Fab")
			(effects
				(font
					(size 1.27 1.27)
				)
			)
		)
		(duplicate_pad_numbers_are_jumpers no)
		(fp_line
			(start 1.249934 6.400038)
			(end -1.249934 6.400038)
			(stroke
				(width 0.1524)
				(type default)
			)
			(layer "F.SilkS")
		)
		(fp_line
			(start 1.249934 -1.320038)
			(end 1.249934 6.400038)
			(stroke
				(width 0.1524)
				(type default)
			)
			(layer "F.SilkS")
		)
		(fp_line
			(start -1.249934 6.400038)
			(end -1.249934 -1.320038)
			(stroke
				(width 0.1524)
				(type default)
			)
			(layer "F.SilkS")
		)
		(fp_line
			(start -1.249934 -1.320038)
			(end 1.249934 -1.320038)
			(stroke
				(width 0.1524)
				(type default)
			)
			(layer "F.SilkS")
		)
		(fp_poly
			(pts
				(xy -1.452372 0) (xy -2.5654 0.556514) (xy -2.5654 -0.556514)
			)
			(stroke
				(width 0)
				(type default)
			)
			(fill yes)
			(layer "F.SilkS")
		)
		(fp_line
			(start 1.249934 6.400038)
			(end -1.249934 6.400038)
			(stroke
				(width 0.1)
				(type default)
			)
			(layer "F.Fab")
		)
		(fp_line
			(start 1.249934 -1.320038)
			(end 1.249934 6.400038)
			(stroke
				(width 0.1)
				(type default)
			)
			(layer "F.Fab")
		)
		(fp_line
			(start -1.249934 6.400038)
			(end -1.249934 -1.320038)
			(stroke
				(width 0.1)
				(type default)
			)
			(layer "F.Fab")
		)
		(fp_line
			(start -1.249934 -1.320038)
			(end 1.249934 -1.320038)
			(stroke
				(width 0.1)
				(type default)
			)
			(layer "F.Fab")
		)
		(fp_poly
			(pts
				(xy -2.5654 -0.556514) (xy -1.452372 0) (xy -2.5654 0.556514)
			)
			(stroke
				(width 0)
				(type default)
			)
			(fill yes)
			(layer "F.Fab")
		)
		(fp_text user "3"
			(at -1.804162 5.177028 0)
			(unlocked yes)
			(layer "F.SilkS")
			(effects
				(font
					(size 0.7874 0.5842)
					(thickness 0.1524)
				)
			)
		)
		(fp_text user "1"
			(at -1.346962 -0.136652 0)
			(unlocked yes)
			(layer "B.SilkS")
			(effects
				(font
					(size 0.7874 0.5842)
					(thickness 0.1524)
				)
				(justify mirror)
			)
		)
		(fp_text user "3"
			(at -1.575562 5.255768 0)
			(unlocked yes)
			(layer "B.SilkS")
			(effects
				(font
					(size 0.7874 0.5842)
					(thickness 0.1524)
				)
				(justify mirror)
			)
		)
		(fp_text user "1"
			(at -1.143 0.02667 180)
			(unlocked yes)
			(layer "B.Fab")
			(effects
				(font
					(size 0.7874 0.5842)
					(thickness 0.1524)
				)
				(justify mirror)
			)
		)
		(fp_text user "3"
			(at -1.1557 5.18287 180)
			(unlocked yes)
			(layer "B.Fab")
			(effects
				(font
					(size 0.7874 0.5842)
					(thickness 0.1524)
				)
				(justify mirror)
			)
		)
		(fp_text user "3"
			(at -1.778 5.13207 180)
			(unlocked yes)
			(layer "F.Fab")
			(effects
				(font
					(size 0.7874 0.5842)
					(thickness 0.1524)
				)
			)
		)
		(pad "1" thru_hole rect
			(at 0 0 180)
			(size 1.5494 1.5494)
			(drill 1.0414)
			(layers "*.Cu" "*.Mask")
			(remove_unused_layers no)
			(net "FM_SMB_PEHPCPU0_PCIE_ALERT_N")
			(clearance 0)
			(padstack
				(mode front_inner_back)
				(layer "Inner"
					(shape circle)
					(size 1.5494 1.5494)
					(clearance 0)
				)
				(layer "B.Cu"
					(shape rect)
					(size 1.5494 1.5494)
					(clearance 0)
				)
			)
		)
		(pad "2" thru_hole circle
			(at 0 2.54 180)
			(size 1.5494 1.5494)
			(drill 1.0414)
			(layers "*.Cu" "*.Mask")
			(remove_unused_layers no)
			(net "GND")
			(clearance 0)
		)
		(pad "3" thru_hole circle
			(at 0 5.08 180)
			(size 1.5494 1.5494)
			(drill 1.0414)
			(layers "*.Cu" "*.Mask")
			(remove_unused_layers no)
			(net "FM_SMB_PEHPCPU1_PCIE_ALERT_N")
			(clearance 0)
		)
	)
	(footprint ""
		(layer "F.Cu")
		(at 389.636 -30.825948 180)
		(property "Reference" "R4613"
			(at 0 0 180)
			(layer "F.SilkS")
			(hide yes)
			(effects
				(font
					(size 1.27 1.27)
				)
			)
		)
		(property "Value" ""
			(at 0 0 180)
			(layer "F.Fab")
			(effects
				(font
					(size 1.27 1.27)
				)
			)
		)
		(duplicate_pad_numbers_are_jumpers no)
		(fp_line
			(start 0.7874 0.4064)
			(end -0.7874 0.4064)
			(stroke
				(width 0.1524)
				(type default)
			)
			(layer "F.SilkS")
		)
		(fp_line
			(start 0.7874 -0.4064)
			(end 0.7874 0.4064)
			(stroke
				(width 0.1524)
				(type default)
			)
			(layer "F.SilkS")
		)
		(fp_line
			(start -0.7874 0.4064)
			(end -0.7874 -0.4064)
			(stroke
				(width 0.1524)
				(type default)
			)
			(layer "F.SilkS")
		)
		(fp_line
			(start -0.7874 -0.4064)
			(end 0.7874 -0.4064)
			(stroke
				(width 0.1524)
				(type default)
			)
			(layer "F.SilkS")
		)
		(fp_line
			(start 0.67945 0.3048)
			(end 0.120396 0.3048)
			(stroke
				(width 0.1)
				(type default)
			)
			(layer "F.Fab")
		)
		(fp_line
			(start 0.67945 -0.3048)
			(end 0.67945 0.3048)
			(stroke
				(width 0.1)
				(type default)
			)
			(layer "F.Fab")
		)
		(fp_line
			(start 0.12065 -0.2794)
			(end 0.12065 -0.3048)
			(stroke
				(width 0.1)
				(type default)
			)
			(layer "F.Fab")
		)
		(fp_line
			(start 0.12065 -0.3048)
			(end 0.67945 -0.3048)
			(stroke
				(width 0.1)
				(type default)
			)
			(layer "F.Fab")
		)
		(fp_line
			(start 0.120396 0.3048)
			(end 0.120396 0.2794)
			(stroke
				(width 0.1)
				(type default)
			)
			(layer "F.Fab")
		)
		(fp_line
			(start 0.120396 0.2794)
			(end -0.12065 0.2794)
			(stroke
				(width 0.1)
				(type default)
			)
			(layer "F.Fab")
		)
		(fp_line
			(start -0.12065 0.3048)
			(end -0.67945 0.3048)
			(stroke
				(width 0.1)
				(type default)
			)
			(layer "F.Fab")
		)
		(fp_line
			(start -0.12065 0.2794)
			(end -0.12065 0.3048)
			(stroke
				(width 0.1)
				(type default)
			)
			(layer "F.Fab")
		)
		(fp_line
			(start -0.12065 -0.2794)
			(end 0.12065 -0.2794)
			(stroke
				(width 0.1)
				(type default)
			)
			(layer "F.Fab")
		)
		(fp_line
			(start -0.12065 -0.305054)
			(end -0.12065 -0.2794)
			(stroke
				(width 0.1)
				(type default)
			)
			(layer "F.Fab")
		)
		(fp_line
			(start -0.67945 0.3048)
			(end -0.67945 -0.305054)
			(stroke
				(width 0.1)
				(type default)
			)
			(layer "F.Fab")
		)
		(fp_line
			(start -0.67945 -0.305054)
			(end -0.12065 -0.305054)
			(stroke
				(width 0.1)
				(type default)
			)
			(layer "F.Fab")
		)
		(pad "1" smd circle
			(at -0.40005 0 180)
			(size 0 0)
			(layers "F.Cu" "F.Mask" "F.Paste")
			(net "OCP_V3_1_P3V3_PWRGD")
		)
		(pad "2" smd circle
			(at 0.40005 0 180)
			(size 0 0)
			(layers "F.Cu" "F.Mask" "F.Paste")
			(net "HP_OCP_V3_1_RST_R")
		)
	)
	(footprint ""
		(layer "F.Cu")
		(at 209.069432 -69.82079)
		(property "Reference" "R1296"
			(at 0 0 0)
			(layer "F.SilkS")
			(hide yes)
			(effects
				(font
					(size 1.27 1.27)
				)
			)
		)
		(property "Value" ""
			(at 0 0 0)
			(layer "F.Fab")
			(effects
				(font
					(size 1.27 1.27)
				)
			)
		)
		(duplicate_pad_numbers_are_jumpers no)
		(fp_line
			(start -0.7874 -0.4064)
			(end 0.7874 -0.4064)
			(stroke
				(width 0.1524)
				(type default)
			)
			(layer "F.SilkS")
		)
		(fp_line
			(start -0.7874 0.4064)
			(end -0.7874 -0.4064)
			(stroke
				(width 0.1524)
				(type default)
			)
			(layer "F.SilkS")
		)
		(fp_line
			(start 0.7874 -0.4064)
			(end 0.7874 0.4064)
			(stroke
				(width 0.1524)
				(type default)
			)
			(layer "F.SilkS")
		)
		(fp_line
			(start 0.7874 0.4064)
			(end -0.7874 0.4064)
			(stroke
				(width 0.1524)
				(type default)
			)
			(layer "F.SilkS")
		)
		(fp_line
			(start -0.67945 -0.305054)
			(end -0.12065 -0.305054)
			(stroke
				(width 0.1)
				(type default)
			)
			(layer "F.Fab")
		)
		(fp_line
			(start -0.67945 0.3048)
			(end -0.67945 -0.305054)
			(stroke
				(width 0.1)
				(type default)
			)
			(layer "F.Fab")
		)
		(fp_line
			(start -0.12065 -0.305054)
			(end -0.12065 -0.2794)
			(stroke
				(width 0.1)
				(type default)
			)
			(layer "F.Fab")
		)
		(fp_line
			(start -0.12065 -0.2794)
			(end 0.12065 -0.2794)
			(stroke
				(width 0.1)
				(type default)
			)
			(layer "F.Fab")
		)
		(fp_line
			(start -0.12065 0.2794)
			(end -0.12065 0.3048)
			(stroke
				(width 0.1)
				(type default)
			)
			(layer "F.Fab")
		)
		(fp_line
			(start -0.12065 0.3048)
			(end -0.67945 0.3048)
			(stroke
				(width 0.1)
				(type default)
			)
			(layer "F.Fab")
		)
		(fp_line
			(start 0.120396 0.2794)
			(end -0.12065 0.2794)
			(stroke
				(width 0.1)
				(type default)
			)
			(layer "F.Fab")
		)
		(fp_line
			(start 0.120396 0.3048)
			(end 0.120396 0.2794)
			(stroke
				(width 0.1)
				(type default)
			)
			(layer "F.Fab")
		)
		(fp_line
			(start 0.12065 -0.3048)
			(end 0.67945 -0.3048)
			(stroke
				(width 0.1)
				(type default)
			)
			(layer "F.Fab")
		)
		(fp_line
			(start 0.12065 -0.2794)
			(end 0.12065 -0.3048)
			(stroke
				(width 0.1)
				(type default)
			)
			(layer "F.Fab")
		)
		(fp_line
			(start 0.67945 -0.3048)
			(end 0.67945 0.3048)
			(stroke
				(width 0.1)
				(type default)
			)
			(layer "F.Fab")
		)
		(fp_line
			(start 0.67945 0.3048)
			(end 0.120396 0.3048)
			(stroke
				(width 0.1)
				(type default)
			)
			(layer "F.Fab")
		)
		(pad "1" smd circle
			(at -0.40005 0)
			(size 0 0)
			(layers "F.Cu" "F.Mask" "F.Paste")
			(net "NCSI_BMC_TXD1_R")
		)
		(pad "2" smd circle
			(at 0.40005 0)
			(size 0 0)
			(layers "F.Cu" "F.Mask" "F.Paste")
			(net "RMII_BMC_OCP_TXD_1")
		)
	)
	(footprint ""
		(layer "F.Cu")
		(at 65.531238 -408.517344 -90)
		(property "Reference" "C699"
			(at 0 0 270)
			(layer "F.SilkS")
			(hide yes)
			(effects
				(font
					(size 1.27 1.27)
				)
			)
		)
		(property "Value" ""
			(at 0 0 270)
			(layer "F.Fab")
			(effects
				(font
					(size 1.27 1.27)
				)
			)
		)
		(duplicate_pad_numbers_are_jumpers no)
		(fp_line
			(start -0.299974 0.150114)
			(end -0.299974 -0.150114)
			(stroke
				(width 0.1)
				(type default)
			)
			(layer "F.Fab")
		)
		(fp_line
			(start 0.299974 0.150114)
			(end -0.299974 0.150114)
			(stroke
				(width 0.1)
				(type default)
			)
			(layer "F.Fab")
		)
		(fp_line
			(start -0.299974 -0.150114)
			(end 0.299974 -0.150114)
			(stroke
				(width 0.1)
				(type default)
			)
			(layer "F.Fab")
		)
		(fp_line
			(start 0.299974 -0.150114)
			(end 0.299974 0.150114)
			(stroke
				(width 0.1)
				(type default)
			)
			(layer "F.Fab")
		)
		(pad "1" smd rect
			(at -0.2667 0 270)
			(size 0.3048 0.381)
			(layers "F.Cu" "F.Mask" "F.Paste")
			(net "P5E_CPU1_PE4_TX_C_DP<5>")
		)
		(pad "2" smd rect
			(at 0.2667 0 270)
			(size 0.3048 0.381)
			(layers "F.Cu" "F.Mask" "F.Paste")
			(net "P5E_CPU1_PE4_TX_DP<5>")
		)
	)
)
